(kicad_pcb
	(version 20260206)
	(generator "pcbnew")
	(generator_version "10.0")
	(general
		(thickness 1.6)
		(legacy_teardrops no)
	)
	(paper "A4")
	(title_block
		(title "01162023_DA0F0TEBIF0_F0T_Expander_BD_F_brd_V02_OCP.brd")
		(comment 1 "Grand Teton / footprints 4249-4256 of 9728")
	)
	(layers
		(0 "F.Cu" signal "TOP")
		(4 "In1.Cu" signal "GND")
		(6 "In2.Cu" signal "VCC")
		(8 "In3.Cu" signal "VCC1")
		(10 "In4.Cu" signal "GND1")
		(12 "In5.Cu" signal "IN1")
		(14 "In6.Cu" signal "GND2")
		(16 "In7.Cu" signal "IN2")
		(18 "In8.Cu" signal "GND3")
		(20 "In9.Cu" signal "IN3")
		(22 "In10.Cu" signal "GND4")
		(24 "In11.Cu" signal "IN4")
		(26 "In12.Cu" signal "GND5")
		(28 "In13.Cu" signal "IN5")
		(30 "In14.Cu" signal "GND6")
		(32 "In15.Cu" signal "IN6")
		(34 "In16.Cu" signal "GND7")
		(2 "B.Cu" signal "BOTTOM")
		(9 "F.Adhes" user "F.Adhesive")
		(11 "B.Adhes" user "B.Adhesive")
		(13 "F.Paste" user "Package Geometry/Pastemask Top")
		(15 "B.Paste" user "Package Geometry/Pastemask Bottom")
		(5 "F.SilkS" user "Ref Des/Silkscreen Top")
		(7 "B.SilkS" user "Ref Des/Silkscreen Bottom")
		(1 "F.Mask" user "Board Geometry/Soldermask Top")
		(3 "B.Mask" user "Board Geometry/Soldermask Bottom")
		(17 "Dwgs.User" user "User.Drawings")
		(19 "Cmts.User" user "User.Comments")
		(21 "Eco1.User" user "User.Eco1")
		(23 "Eco2.User" user "User.Eco2")
		(25 "Edge.Cuts" user "Board Geometry/Outline")
		(27 "Margin" user)
		(31 "F.CrtYd" user "Package Geometry/Place Bound Top")
		(29 "B.CrtYd" user "Package Geometry/Place Bound Bottom")
		(35 "F.Fab" user "Ref Des/Assembly Top")
		(33 "B.Fab" user "Ref Des/Assembly Bottom")
	)
	(footprint ""
		(layer "F.Cu")
		(at 435.055772 -350.098614 90)
		(property "Reference" "C2464"
			(at 0 0 90)
			(layer "F.SilkS")
			(hide yes)
			(effects
				(font
					(size 1.27 1.27)
				)
			)
		)
		(property "Value" ""
			(at 0 0 90)
			(layer "F.Fab")
			(effects
				(font
					(size 1.27 1.27)
				)
			)
		)
		(duplicate_pad_numbers_are_jumpers no)
		(fp_line
			(start 0.299974 -0.150114)
			(end 0.299974 0.150114)
			(stroke
				(width 0.1)
				(type default)
			)
			(layer "F.Fab")
		)
		(fp_line
			(start -0.299974 -0.150114)
			(end 0.299974 -0.150114)
			(stroke
				(width 0.1)
				(type default)
			)
			(layer "F.Fab")
		)
		(fp_line
			(start 0.299974 0.150114)
			(end -0.299974 0.150114)
			(stroke
				(width 0.1)
				(type default)
			)
			(layer "F.Fab")
		)
		(fp_line
			(start -0.299974 0.150114)
			(end -0.299974 -0.150114)
			(stroke
				(width 0.1)
				(type default)
			)
			(layer "F.Fab")
		)
		(pad "1" smd rect
			(at -0.2667 0 90)
			(size 0.3048 0.381)
			(layers "F.Cu" "F.Mask" "F.Paste")
			(net "P5E_PEX3_STN4_TX_DN<67>")
		)
		(pad "2" smd rect
			(at 0.2667 0 90)
			(size 0.3048 0.381)
			(layers "F.Cu" "F.Mask" "F.Paste")
			(net "P5E_PEX3_STN4_TX_C_DN<67>")
		)
	)
	(footprint ""
		(layer "F.Cu")
		(at 361.89031 -258.131564 180)
		(property "Reference" "R839"
			(at 0 0 180)
			(layer "F.SilkS")
			(hide yes)
			(effects
				(font
					(size 1.27 1.27)
				)
			)
		)
		(property "Value" ""
			(at 0 0 180)
			(layer "F.Fab")
			(effects
				(font
					(size 1.27 1.27)
				)
			)
		)
		(duplicate_pad_numbers_are_jumpers no)
		(fp_line
			(start 0.7874 0.4064)
			(end -0.7874 0.4064)
			(stroke
				(width 0.1524)
				(type default)
			)
			(layer "F.SilkS")
		)
		(fp_line
			(start 0.7874 -0.4064)
			(end 0.7874 0.4064)
			(stroke
				(width 0.1524)
				(type default)
			)
			(layer "F.SilkS")
		)
		(fp_line
			(start -0.7874 0.4064)
			(end -0.7874 -0.4064)
			(stroke
				(width 0.1524)
				(type default)
			)
			(layer "F.SilkS")
		)
		(fp_line
			(start -0.7874 -0.4064)
			(end 0.7874 -0.4064)
			(stroke
				(width 0.1524)
				(type default)
			)
			(layer "F.SilkS")
		)
		(fp_line
			(start 0.67945 0.3048)
			(end 0.120396 0.3048)
			(stroke
				(width 0.1)
				(type default)
			)
			(layer "F.Fab")
		)
		(fp_line
			(start 0.67945 -0.3048)
			(end 0.67945 0.3048)
			(stroke
				(width 0.1)
				(type default)
			)
			(layer "F.Fab")
		)
		(fp_line
			(start 0.12065 -0.2794)
			(end 0.12065 -0.3048)
			(stroke
				(width 0.1)
				(type default)
			)
			(layer "F.Fab")
		)
		(fp_line
			(start 0.12065 -0.3048)
			(end 0.67945 -0.3048)
			(stroke
				(width 0.1)
				(type default)
			)
			(layer "F.Fab")
		)
		(fp_line
			(start 0.120396 0.3048)
			(end 0.120396 0.2794)
			(stroke
				(width 0.1)
				(type default)
			)
			(layer "F.Fab")
		)
		(fp_line
			(start 0.120396 0.2794)
			(end -0.12065 0.2794)
			(stroke
				(width 0.1)
				(type default)
			)
			(layer "F.Fab")
		)
		(fp_line
			(start -0.12065 0.3048)
			(end -0.67945 0.3048)
			(stroke
				(width 0.1)
				(type default)
			)
			(layer "F.Fab")
		)
		(fp_line
			(start -0.12065 0.2794)
			(end -0.12065 0.3048)
			(stroke
				(width 0.1)
				(type default)
			)
			(layer "F.Fab")
		)
		(fp_line
			(start -0.12065 -0.2794)
			(end 0.12065 -0.2794)
			(stroke
				(width 0.1)
				(type default)
			)
			(layer "F.Fab")
		)
		(fp_line
			(start -0.12065 -0.305054)
			(end -0.12065 -0.2794)
			(stroke
				(width 0.1)
				(type default)
			)
			(layer "F.Fab")
		)
		(fp_line
			(start -0.67945 0.3048)
			(end -0.67945 -0.305054)
			(stroke
				(width 0.1)
				(type default)
			)
			(layer "F.Fab")
		)
		(fp_line
			(start -0.67945 -0.305054)
			(end -0.12065 -0.305054)
			(stroke
				(width 0.1)
				(type default)
			)
			(layer "F.Fab")
		)
		(pad "1" smd circle
			(at -0.40005 0 180)
			(size 0 0)
			(layers "F.Cu" "F.Mask" "F.Paste")
			(net "P3V3_AUX")
		)
		(pad "2" smd circle
			(at 0.40005 0 180)
			(size 0 0)
			(layers "F.Cu" "F.Mask" "F.Paste")
			(net "P0V8_PEX3_BVRRDY")
		)
	)
	(footprint ""
		(layer "F.Cu")
		(at 448.343274 -258.331208 -90)
		(property "Reference" "R6551"
			(at 0 0 270)
			(layer "F.SilkS")
			(hide yes)
			(effects
				(font
					(size 1.27 1.27)
				)
			)
		)
		(property "Value" ""
			(at 0 0 270)
			(layer "F.Fab")
			(effects
				(font
					(size 1.27 1.27)
				)
			)
		)
		(duplicate_pad_numbers_are_jumpers no)
		(fp_line
			(start -0.7874 0.4064)
			(end -0.7874 -0.4064)
			(stroke
				(width 0.1524)
				(type default)
			)
			(layer "F.SilkS")
		)
		(fp_line
			(start 0.7874 0.4064)
			(end -0.7874 0.4064)
			(stroke
				(width 0.1524)
				(type default)
			)
			(layer "F.SilkS")
		)
		(fp_line
			(start -0.7874 -0.4064)
			(end 0.7874 -0.4064)
			(stroke
				(width 0.1524)
				(type default)
			)
			(layer "F.SilkS")
		)
		(fp_line
			(start 0.7874 -0.4064)
			(end 0.7874 0.4064)
			(stroke
				(width 0.1524)
				(type default)
			)
			(layer "F.SilkS")
		)
		(fp_line
			(start -0.67945 0.3048)
			(end -0.67945 -0.305054)
			(stroke
				(width 0.1)
				(type default)
			)
			(layer "F.Fab")
		)
		(fp_line
			(start -0.12065 0.3048)
			(end -0.67945 0.3048)
			(stroke
				(width 0.1)
				(type default)
			)
			(layer "F.Fab")
		)
		(fp_line
			(start 0.120396 0.3048)
			(end 0.120396 0.2794)
			(stroke
				(width 0.1)
				(type default)
			)
			(layer "F.Fab")
		)
		(fp_line
			(start 0.67945 0.3048)
			(end 0.120396 0.3048)
			(stroke
				(width 0.1)
				(type default)
			)
			(layer "F.Fab")
		)
		(fp_line
			(start -0.12065 0.2794)
			(end -0.12065 0.3048)
			(stroke
				(width 0.1)
				(type default)
			)
			(layer "F.Fab")
		)
		(fp_line
			(start 0.120396 0.2794)
			(end -0.12065 0.2794)
			(stroke
				(width 0.1)
				(type default)
			)
			(layer "F.Fab")
		)
		(fp_line
			(start -0.12065 -0.2794)
			(end 0.12065 -0.2794)
			(stroke
				(width 0.1)
				(type default)
			)
			(layer "F.Fab")
		)
		(fp_line
			(start 0.12065 -0.2794)
			(end 0.12065 -0.3048)
			(stroke
				(width 0.1)
				(type default)
			)
			(layer "F.Fab")
		)
		(fp_line
			(start 0.12065 -0.3048)
			(end 0.67945 -0.3048)
			(stroke
				(width 0.1)
				(type default)
			)
			(layer "F.Fab")
		)
		(fp_line
			(start 0.67945 -0.3048)
			(end 0.67945 0.3048)
			(stroke
				(width 0.1)
				(type default)
			)
			(layer "F.Fab")
		)
		(fp_line
			(start -0.67945 -0.305054)
			(end -0.12065 -0.305054)
			(stroke
				(width 0.1)
				(type default)
			)
			(layer "F.Fab")
		)
		(fp_line
			(start -0.12065 -0.305054)
			(end -0.12065 -0.2794)
			(stroke
				(width 0.1)
				(type default)
			)
			(layer "F.Fab")
		)
		(pad "1" smd circle
			(at -0.40005 0 270)
			(size 0 0)
			(layers "F.Cu" "F.Mask" "F.Paste")
			(net "P1V25_SERDES_VDDPLL_PEX3")
		)
		(pad "2" smd circle
			(at 0.40005 0 270)
			(size 0 0)
			(layers "F.Cu" "F.Mask" "F.Paste")
			(net "P1V25_SERDES_VDDPLL_PEX3_C0")
		)
	)
	(footprint ""
		(layer "F.Cu")
		(at 51.311048 -350.098614 90)
		(property "Reference" "C162"
			(at 0 0 90)
			(layer "F.SilkS")
			(hide yes)
			(effects
				(font
					(size 1.27 1.27)
				)
			)
		)
		(property "Value" ""
			(at 0 0 90)
			(layer "F.Fab")
			(effects
				(font
					(size 1.27 1.27)
				)
			)
		)
		(duplicate_pad_numbers_are_jumpers no)
		(fp_line
			(start 0.299974 -0.150114)
			(end 0.299974 0.150114)
			(stroke
				(width 0.1)
				(type default)
			)
			(layer "F.Fab")
		)
		(fp_line
			(start -0.299974 -0.150114)
			(end 0.299974 -0.150114)
			(stroke
				(width 0.1)
				(type default)
			)
			(layer "F.Fab")
		)
		(fp_line
			(start 0.299974 0.150114)
			(end -0.299974 0.150114)
			(stroke
				(width 0.1)
				(type default)
			)
			(layer "F.Fab")
		)
		(fp_line
			(start -0.299974 0.150114)
			(end -0.299974 -0.150114)
			(stroke
				(width 0.1)
				(type default)
			)
			(layer "F.Fab")
		)
		(pad "1" smd rect
			(at -0.2667 0 90)
			(size 0.3048 0.381)
			(layers "F.Cu" "F.Mask" "F.Paste")
			(net "P5E_PEX0_STN7_TX_DN<127>")
		)
		(pad "2" smd rect
			(at 0.2667 0 90)
			(size 0.3048 0.381)
			(layers "F.Cu" "F.Mask" "F.Paste")
			(net "P5E_PEX0_STN7_TX_C_DN<127>")
		)
	)
	(footprint ""
		(layer "F.Cu")
		(at 308.31536 -42.853102 180)
		(property "Reference" "R5900"
			(at 0 0 180)
			(layer "F.SilkS")
			(hide yes)
			(effects
				(font
					(size 1.27 1.27)
				)
			)
		)
		(property "Value" ""
			(at 0 0 180)
			(layer "F.Fab")
			(effects
				(font
					(size 1.27 1.27)
				)
			)
		)
		(duplicate_pad_numbers_are_jumpers no)
		(fp_line
			(start 0.7874 0.4064)
			(end -0.7874 0.4064)
			(stroke
				(width 0.1524)
				(type default)
			)
			(layer "F.SilkS")
		)
		(fp_line
			(start 0.7874 -0.4064)
			(end 0.7874 0.4064)
			(stroke
				(width 0.1524)
				(type default)
			)
			(layer "F.SilkS")
		)
		(fp_line
			(start -0.7874 0.4064)
			(end -0.7874 -0.4064)
			(stroke
				(width 0.1524)
				(type default)
			)
			(layer "F.SilkS")
		)
		(fp_line
			(start -0.7874 -0.4064)
			(end 0.7874 -0.4064)
			(stroke
				(width 0.1524)
				(type default)
			)
			(layer "F.SilkS")
		)
		(fp_line
			(start 0.67945 0.3048)
			(end 0.120396 0.3048)
			(stroke
				(width 0.1)
				(type default)
			)
			(layer "F.Fab")
		)
		(fp_line
			(start 0.67945 -0.3048)
			(end 0.67945 0.3048)
			(stroke
				(width 0.1)
				(type default)
			)
			(layer "F.Fab")
		)
		(fp_line
			(start 0.12065 -0.2794)
			(end 0.12065 -0.3048)
			(stroke
				(width 0.1)
				(type default)
			)
			(layer "F.Fab")
		)
		(fp_line
			(start 0.12065 -0.3048)
			(end 0.67945 -0.3048)
			(stroke
				(width 0.1)
				(type default)
			)
			(layer "F.Fab")
		)
		(fp_line
			(start 0.120396 0.3048)
			(end 0.120396 0.2794)
			(stroke
				(width 0.1)
				(type default)
			)
			(layer "F.Fab")
		)
		(fp_line
			(start 0.120396 0.2794)
			(end -0.12065 0.2794)
			(stroke
				(width 0.1)
				(type default)
			)
			(layer "F.Fab")
		)
		(fp_line
			(start -0.12065 0.3048)
			(end -0.67945 0.3048)
			(stroke
				(width 0.1)
				(type default)
			)
			(layer "F.Fab")
		)
		(fp_line
			(start -0.12065 0.2794)
			(end -0.12065 0.3048)
			(stroke
				(width 0.1)
				(type default)
			)
			(layer "F.Fab")
		)
		(fp_line
			(start -0.12065 -0.2794)
			(end 0.12065 -0.2794)
			(stroke
				(width 0.1)
				(type default)
			)
			(layer "F.Fab")
		)
		(fp_line
			(start -0.12065 -0.305054)
			(end -0.12065 -0.2794)
			(stroke
				(width 0.1)
				(type default)
			)
			(layer "F.Fab")
		)
		(fp_line
			(start -0.67945 0.3048)
			(end -0.67945 -0.305054)
			(stroke
				(width 0.1)
				(type default)
			)
			(layer "F.Fab")
		)
		(fp_line
			(start -0.67945 -0.305054)
			(end -0.12065 -0.305054)
			(stroke
				(width 0.1)
				(type default)
			)
			(layer "F.Fab")
		)
		(pad "1" smd circle
			(at -0.40005 0 180)
			(size 0 0)
			(layers "F.Cu" "F.Mask" "F.Paste")
			(net "SSD10_ADC_A1")
		)
		(pad "2" smd circle
			(at 0.40005 0 180)
			(size 0 0)
			(layers "F.Cu" "F.Mask" "F.Paste")
			(net "SMB_SSD10_ADC_SDA")
		)
	)
	(footprint ""
		(layer "F.Cu")
		(at 298.57319 -213.523068 -90)
		(property "Reference" "R3399"
			(at 0 0 270)
			(layer "F.SilkS")
			(hide yes)
			(effects
				(font
					(size 1.27 1.27)
				)
			)
		)
		(property "Value" ""
			(at 0 0 270)
			(layer "F.Fab")
			(effects
				(font
					(size 1.27 1.27)
				)
			)
		)
		(duplicate_pad_numbers_are_jumpers no)
		(fp_line
			(start -0.7874 0.4064)
			(end -0.7874 -0.4064)
			(stroke
				(width 0.1524)
				(type default)
			)
			(layer "F.SilkS")
		)
		(fp_line
			(start 0.7874 0.4064)
			(end -0.7874 0.4064)
			(stroke
				(width 0.1524)
				(type default)
			)
			(layer "F.SilkS")
		)
		(fp_line
			(start -0.7874 -0.4064)
			(end 0.7874 -0.4064)
			(stroke
				(width 0.1524)
				(type default)
			)
			(layer "F.SilkS")
		)
		(fp_line
			(start 0.7874 -0.4064)
			(end 0.7874 0.4064)
			(stroke
				(width 0.1524)
				(type default)
			)
			(layer "F.SilkS")
		)
		(fp_line
			(start -0.67945 0.3048)
			(end -0.67945 -0.305054)
			(stroke
				(width 0.1)
				(type default)
			)
			(layer "F.Fab")
		)
		(fp_line
			(start -0.12065 0.3048)
			(end -0.67945 0.3048)
			(stroke
				(width 0.1)
				(type default)
			)
			(layer "F.Fab")
		)
		(fp_line
			(start 0.120396 0.3048)
			(end 0.120396 0.2794)
			(stroke
				(width 0.1)
				(type default)
			)
			(layer "F.Fab")
		)
		(fp_line
			(start 0.67945 0.3048)
			(end 0.120396 0.3048)
			(stroke
				(width 0.1)
				(type default)
			)
			(layer "F.Fab")
		)
		(fp_line
			(start -0.12065 0.2794)
			(end -0.12065 0.3048)
			(stroke
				(width 0.1)
				(type default)
			)
			(layer "F.Fab")
		)
		(fp_line
			(start 0.120396 0.2794)
			(end -0.12065 0.2794)
			(stroke
				(width 0.1)
				(type default)
			)
			(layer "F.Fab")
		)
		(fp_line
			(start -0.12065 -0.2794)
			(end 0.12065 -0.2794)
			(stroke
				(width 0.1)
				(type default)
			)
			(layer "F.Fab")
		)
		(fp_line
			(start 0.12065 -0.2794)
			(end 0.12065 -0.3048)
			(stroke
				(width 0.1)
				(type default)
			)
			(layer "F.Fab")
		)
		(fp_line
			(start 0.12065 -0.3048)
			(end 0.67945 -0.3048)
			(stroke
				(width 0.1)
				(type default)
			)
			(layer "F.Fab")
		)
		(fp_line
			(start 0.67945 -0.3048)
			(end 0.67945 0.3048)
			(stroke
				(width 0.1)
				(type default)
			)
			(layer "F.Fab")
		)
		(fp_line
			(start -0.67945 -0.305054)
			(end -0.12065 -0.305054)
			(stroke
				(width 0.1)
				(type default)
			)
			(layer "F.Fab")
		)
		(fp_line
			(start -0.12065 -0.305054)
			(end -0.12065 -0.2794)
			(stroke
				(width 0.1)
				(type default)
			)
			(layer "F.Fab")
		)
		(pad "1" smd circle
			(at -0.40005 0 270)
			(size 0 0)
			(layers "F.Cu" "F.Mask" "F.Paste")
			(net "SPI_BIC1_CLK_LS23_R2")
		)
		(pad "2" smd circle
			(at 0.40005 0 270)
			(size 0 0)
			(layers "F.Cu" "F.Mask" "F.Paste")
			(net "SPI_BIC1_CLK_LS23_R")
		)
	)
	(footprint ""
		(layer "F.Cu")
		(at 227.375466 -104.557322 -90)
		(property "Reference" "PC341"
			(at 0 0 270)
			(layer "F.SilkS")
			(hide yes)
			(effects
				(font
					(size 1.27 1.27)
				)
			)
		)
		(property "Value" ""
			(at 0 0 270)
			(layer "F.Fab")
			(effects
				(font
					(size 1.27 1.27)
				)
			)
		)
		(duplicate_pad_numbers_are_jumpers no)
		(fp_line
			(start -1.524 0.762)
			(end -1.524 -0.762)
			(stroke
				(width 0.1524)
				(type default)
			)
			(layer "F.SilkS")
		)
		(fp_line
			(start 1.524 0.762)
			(end -1.524 0.762)
			(stroke
				(width 0.1524)
				(type default)
			)
			(layer "F.SilkS")
		)
		(fp_line
			(start -1.524 -0.762)
			(end 1.524 -0.762)
			(stroke
				(width 0.1524)
				(type default)
			)
			(layer "F.SilkS")
		)
		(fp_line
			(start 1.524 -0.762)
			(end 1.524 0.762)
			(stroke
				(width 0.1524)
				(type default)
			)
			(layer "F.SilkS")
		)
		(fp_line
			(start -1.1049 0.724916)
			(end 1.1049 0.724916)
			(stroke
				(width 0.1)
				(type default)
			)
			(layer "F.Fab")
		)
		(fp_line
			(start 1.1049 0.724916)
			(end 1.1049 -0.724916)
			(stroke
				(width 0.1)
				(type default)
			)
			(layer "F.Fab")
		)
		(fp_line
			(start -1.1049 -0.724916)
			(end -1.1049 0.724916)
			(stroke
				(width 0.1)
				(type default)
			)
			(layer "F.Fab")
		)
		(fp_line
			(start 1.1049 -0.724916)
			(end -1.1049 -0.724916)
			(stroke
				(width 0.1)
				(type default)
			)
			(layer "F.Fab")
		)
		(pad "1" smd rect
			(at -0.889 0 90)
			(size 1.016 1.27)
			(layers "F.Cu" "F.Mask" "F.Paste")
			(net "GND")
		)
		(pad "2" smd rect
			(at 0.889 0 90)
			(size 1.016 1.27)
			(layers "F.Cu" "F.Mask" "F.Paste")
			(net "P12V_AUX")
		)
	)
	(footprint ""
		(layer "F.Cu")
		(at 259.130038 -290.805108 -90)
		(property "Reference" "C3381"
			(at 0 0 270)
			(layer "F.SilkS")
			(hide yes)
			(effects
				(font
					(size 1.27 1.27)
				)
			)
		)
		(property "Value" ""
			(at 0 0 270)
			(layer "F.Fab")
			(effects
				(font
					(size 1.27 1.27)
				)
			)
		)
		(duplicate_pad_numbers_are_jumpers no)
		(fp_line
			(start -1.2954 0.5842)
			(end -1.2954 -0.5842)
			(stroke
				(width 0.1524)
				(type default)
			)
			(layer "F.SilkS")
		)
		(fp_line
			(start 1.2954 0.5842)
			(end -1.2954 0.5842)
			(stroke
				(width 0.1524)
				(type default)
			)
			(layer "F.SilkS")
		)
		(fp_line
			(start -1.2954 -0.5842)
			(end 1.2954 -0.5842)
			(stroke
				(width 0.1524)
				(type default)
			)
			(layer "F.SilkS")
		)
		(fp_line
			(start 1.2954 -0.5842)
			(end 1.2954 0.5842)
			(stroke
				(width 0.1524)
				(type default)
			)
			(layer "F.SilkS")
		)
		(fp_line
			(start -0.8636 0.4572)
			(end -0.8636 0.4064)
			(stroke
				(width 0.1)
				(type default)
			)
			(layer "F.Fab")
		)
		(fp_line
			(start 0.8636 0.4572)
			(end -0.8636 0.4572)
			(stroke
				(width 0.1)
				(type default)
			)
			(layer "F.Fab")
		)
		(fp_line
			(start -1.1938 0.4064)
			(end -1.1938 -0.4064)
			(stroke
				(width 0.1)
				(type default)
			)
			(layer "F.Fab")
		)
		(fp_line
			(start -0.8636 0.4064)
			(end -1.1938 0.4064)
			(stroke
				(width 0.1)
				(type default)
			)
			(layer "F.Fab")
		)
		(fp_line
			(start 0.8636 0.4064)
			(end 0.8636 0.4572)
			(stroke
				(width 0.1)
				(type default)
			)
			(layer "F.Fab")
		)
		(fp_line
			(start 1.1938 0.4064)
			(end 0.8636 0.4064)
			(stroke
				(width 0.1)
				(type default)
			)
			(layer "F.Fab")
		)
		(fp_line
			(start -1.1938 -0.4064)
			(end -0.8636 -0.4064)
			(stroke
				(width 0.1)
				(type default)
			)
			(layer "F.Fab")
		)
		(fp_line
			(start -0.8636 -0.4064)
			(end -0.8636 -0.4572)
			(stroke
				(width 0.1)
				(type default)
			)
			(layer "F.Fab")
		)
		(fp_line
			(start 0.8636 -0.4064)
			(end 1.1938 -0.4064)
			(stroke
				(width 0.1)
				(type default)
			)
			(layer "F.Fab")
		)
		(fp_line
			(start 1.1938 -0.4064)
			(end 1.1938 0.4064)
			(stroke
				(width 0.1)
				(type default)
			)
			(layer "F.Fab")
		)
		(fp_line
			(start -0.8636 -0.4572)
			(end 0.8636 -0.4572)
			(stroke
				(width 0.1)
				(type default)
			)
			(layer "F.Fab")
		)
		(fp_line
			(start 0.8636 -0.4572)
			(end 0.8636 -0.4064)
			(stroke
				(width 0.1)
				(type default)
			)
			(layer "F.Fab")
		)
		(pad "1" smd rect
			(at -0.7366 0 180)
			(size 0.7112 0.8128)
			(layers "F.Cu" "F.Mask" "F.Paste")
			(net "P1V8_PLL0_PEX2")
		)
		(pad "2" smd rect
			(at 0.7366 0 180)
			(size 0.7112 0.8128)
			(layers "F.Cu" "F.Mask" "F.Paste")
			(net "GND")
		)
	)
)
